# S9S_MB_2U (Grand Teton) — schematic netlist excerpt (pin names and nets, part order shuffled) for the footprints in the layout excerpt that follows; sources: Cadence DE-HDL packaged netlist, KiCad conversion of 03242023_DA0F0TMBIJ0_F0T_Motherboard_J_brd_V01_OCP.brd

J82  PICOPROBE_BXA  DELTA-L 4.0 EMPTY  pkg TRIANG_LAUNCH_3PXB  page 308
  \1_p\  = DELTA_L_85_10INCH_BOT_DN
  \2_n\  = DELTA_L_85_10INCH_BOT_DP
  \3_g\  = DELTA_L_GND_1

(kicad_pcb
	(version 20260206)
	(generator "pcbnew")
	(generator_version "10.0")
	(general
		(thickness 1.6)
		(legacy_teardrops no)
	)
	(paper "A4")
	(title_block
		(title "03242023_DA0F0TMBIJ0_F0T_Motherboard_J_brd_V01_OCP.brd")
		(comment 1 "Grand Teton / footprints 4716-4716 of 6105")
	)
	(layers
		(0 "F.Cu" signal "TOP")
		(4 "In1.Cu" signal "GND")
		(6 "In2.Cu" signal "IN1")
		(8 "In3.Cu" signal "GND1")
		(10 "In4.Cu" signal "IN2")
		(12 "In5.Cu" signal "GND2")
		(14 "In6.Cu" signal "IN3")
		(16 "In7.Cu" signal "GND3")
		(18 "In8.Cu" signal "VCC")
		(20 "In9.Cu" signal "VCC1")
		(22 "In10.Cu" signal "GND4")
		(24 "In11.Cu" signal "IN4")
		(26 "In12.Cu" signal "GND5")
		(28 "In13.Cu" signal "IN5")
		(30 "In14.Cu" signal "GND6")
		(32 "In15.Cu" signal "IN6")
		(34 "In16.Cu" signal "GND7")
		(2 "B.Cu" signal "BOTTOM")
		(9 "F.Adhes" user "F.Adhesive")
		(11 "B.Adhes" user "B.Adhesive")
		(13 "F.Paste" user "Package Geometry/Pastemask Top")
		(15 "B.Paste" user "Package Geometry/Pastemask Bottom")
		(5 "F.SilkS" user "Ref Des/Silkscreen Top")
		(7 "B.SilkS" user "Ref Des/Silkscreen Bottom")
		(1 "F.Mask" user "Board Geometry/Soldermask Top")
		(3 "B.Mask" user "Board Geometry/Soldermask Bottom")
		(17 "Dwgs.User" user "User.Drawings")
		(19 "Cmts.User" user "User.Comments")
		(21 "Eco1.User" user "User.Eco1")
		(23 "Eco2.User" user "User.Eco2")
		(25 "Edge.Cuts" user "Board Geometry/Outline")
		(27 "Margin" user)
		(31 "F.CrtYd" user "Package Geometry/Place Bound Top")
		(29 "B.CrtYd" user "Package Geometry/Place Bound Bottom")
		(35 "F.Fab" user "Ref Des/Assembly Top")
		(33 "B.Fab" user "Ref Des/Assembly Bottom")
	)
	(footprint ""
		(layer "B.Cu")
		(at 329.240388 -2.156206)
		(property "Reference" "J82"
			(at 4.361942 1.140206 270)
			(unlocked yes)
			(layer "B.SilkS")
			(effects
				(font
					(size 0.7874 0.5842)
					(thickness 0.1524)
				)
				(justify left mirror)
			)
		)
		(property "Value" ""
			(at 0 0 0)
			(layer "B.Fab")
			(effects
				(font
					(size 1.27 1.27)
				)
				(justify mirror)
			)
		)
		(duplicate_pad_numbers_are_jumpers no)
		(fp_line
			(start -1.2192 -2.1082)
			(end -1.2192 2.1082)
			(stroke
				(width 0.1524)
				(type default)
			)
			(layer "B.SilkS")
		)
		(fp_line
			(start -1.2192 2.1082)
			(end 1.2192 2.1082)
			(stroke
				(width 0.1524)
				(type default)
			)
			(layer "B.SilkS")
		)
		(fp_line
			(start 1.2192 -2.1082)
			(end -1.2192 -2.1082)
			(stroke
				(width 0.1524)
				(type default)
			)
			(layer "B.SilkS")
		)
		(fp_line
			(start 1.2192 2.1082)
			(end 1.2192 -2.1082)
			(stroke
				(width 0.1524)
				(type default)
			)
			(layer "B.SilkS")
		)
		(pad "" np_thru_hole circle
			(at -3.4671 -1.27 270)
			(size 1.0414 1.0414)
			(drill 1.0414)
			(layers "*.Cu" "*.Mask")
			(clearance 0.381)
			(thermal_gap 0.381)
		)
		(pad "" np_thru_hole circle
			(at -3.4671 1.27 270)
			(size 1.0414 1.0414)
			(drill 1.0414)
			(layers "*.Cu" "*.Mask")
			(clearance 0.381)
			(thermal_gap 0.381)
		)
		(pad "" np_thru_hole circle
			(at 2.8829 -1.27 270)
			(size 1.0414 1.0414)
			(drill 1.0414)
			(layers "*.Cu" "*.Mask")
			(clearance 0.381)
			(thermal_gap 0.381)
		)
		(pad "" np_thru_hole circle
			(at 2.8829 1.27 270)
			(size 1.0414 1.0414)
			(drill 1.0414)
			(layers "*.Cu" "*.Mask")
			(clearance 0.381)
			(thermal_gap 0.381)
		)
		(pad "1" smd rect
			(at -0.8255 -0.249936 270)
			(size 0.3048 0.508)
			(layers "B.Cu" "B.Mask" "B.Paste")
			(net "DELTA_L_85_10INCH_BOT_DN")
		)
		(pad "2" smd rect
			(at -0.8255 0.249936 270)
			(size 0.3048 0.508)
			(layers "B.Cu" "B.Mask" "B.Paste")
			(net "DELTA_L_85_10INCH_BOT_DP")
		)
		(pad "3" smd circle
			(at 0 0 180)
			(size 0 0)
			(layers "B.Cu" "B.Mask" "B.Paste")
			(net "DELTA_L_GND_1")
		)
		(zone
			(layers "F.Cu" "B.Cu" "In1.Cu" "In2.Cu" "In3.Cu" "In4.Cu" "In5.Cu" "In6.Cu"
				"In7.Cu" "In8.Cu" "In9.Cu" "In10.Cu" "In11.Cu" "In12.Cu" "In13.Cu" "In14.Cu"
				"In15.Cu" "In16.Cu"
			)
			(hatch none 0.5)
			(connect_pads
				(clearance 0)
			)
			(min_thickness 0.25)
			(keepout
				(tracks not_allowed)
				(vias allowed)
				(pads allowed)
				(copperpour not_allowed)
				(footprints allowed)
			)
			(placement
				(enabled no)
				(sheetname "")
			)
			(fill
				(thermal_gap 0.5)
				(thermal_bridge_width 0.5)
				(island_removal_mode 0)
			)
			(polygon
				(pts
					(arc
						(start 326.700388 -3.426206)
						(mid 324.846188 -3.426206)
						(end 326.700388 -3.426206)
					)
				)
			)
		)
		(zone
			(layers "F.Cu" "B.Cu" "In1.Cu" "In2.Cu" "In3.Cu" "In4.Cu" "In5.Cu" "In6.Cu"
				"In7.Cu" "In8.Cu" "In9.Cu" "In10.Cu" "In11.Cu" "In12.Cu" "In13.Cu" "In14.Cu"
				"In15.Cu" "In16.Cu"
			)
			(hatch none 0.5)
			(connect_pads
				(clearance 0)
			)
			(min_thickness 0.25)
			(keepout
				(tracks not_allowed)
				(vias allowed)
				(pads allowed)
				(copperpour not_allowed)
				(footprints allowed)
			)
			(placement
				(enabled no)
				(sheetname "")
			)
			(fill
				(thermal_gap 0.5)
				(thermal_bridge_width 0.5)
				(island_removal_mode 0)
			)
			(polygon
				(pts
					(arc
						(start 326.700388 -0.886206)
						(mid 324.846188 -0.886206)
						(end 326.700388 -0.886206)
					)
				)
			)
		)
		(zone
			(layers "F.Cu" "B.Cu" "In1.Cu" "In2.Cu" "In3.Cu" "In4.Cu" "In5.Cu" "In6.Cu"
				"In7.Cu" "In8.Cu" "In9.Cu" "In10.Cu" "In11.Cu" "In12.Cu" "In13.Cu" "In14.Cu"
				"In15.Cu" "In16.Cu"
			)
			(hatch none 0.5)
			(connect_pads
				(clearance 0)
			)
			(min_thickness 0.25)
			(keepout
				(tracks not_allowed)
				(vias allowed)
				(pads allowed)
				(copperpour not_allowed)
				(footprints allowed)
			)
			(placement
				(enabled no)
				(sheetname "")
			)
			(fill
				(thermal_gap 0.5)
				(thermal_bridge_width 0.5)
				(island_removal_mode 0)
			)
			(polygon
				(pts
					(arc
						(start 333.050388 -3.426206)
						(mid 331.196188 -3.426206)
						(end 333.050388 -3.426206)
					)
				)
			)
		)
		(zone
			(layers "F.Cu" "B.Cu" "In1.Cu" "In2.Cu" "In3.Cu" "In4.Cu" "In5.Cu" "In6.Cu"
				"In7.Cu" "In8.Cu" "In9.Cu" "In10.Cu" "In11.Cu" "In12.Cu" "In13.Cu" "In14.Cu"
				"In15.Cu" "In16.Cu"
			)
			(hatch none 0.5)
			(connect_pads
				(clearance 0)
			)
			(min_thickness 0.25)
			(keepout
				(tracks not_allowed)
				(vias allowed)
				(pads allowed)
				(copperpour not_allowed)
				(footprints allowed)
			)
			(placement
				(enabled no)
				(sheetname "")
			)
			(fill
				(thermal_gap 0.5)
				(thermal_bridge_width 0.5)
				(island_removal_mode 0)
			)
			(polygon
				(pts
					(arc
						(start 333.050388 -0.886206)
						(mid 331.196188 -0.886206)
						(end 333.050388 -0.886206)
					)
				)
			)
		)
		(zone
			(layer "B.Cu")
			(hatch none 0.5)
			(connect_pads
				(clearance 0)
			)
			(min_thickness 0.25)
			(keepout
				(tracks not_allowed)
				(vias allowed)
				(pads allowed)
				(copperpour not_allowed)
				(footprints allowed)
			)
			(placement
				(enabled no)
				(sheetname "")
			)
			(fill
				(thermal_gap 0.5)
				(thermal_bridge_width 0.5)
				(island_removal_mode 0)
			)
			(polygon
				(pts
					(xy 328.122788 -2.704846) (xy 328.122788 -2.609342) (xy 328.719688 -2.609342) (xy 328.719688 -2.202942)
					(xy 328.122788 -2.202942) (xy 328.122788 -2.10947) (xy 328.719688 -2.10947) (xy 328.719688 -1.70307)
					(xy 328.122788 -1.70307) (xy 328.122788 -1.607566) (xy 328.821288 -1.607566) (xy 328.821288 -2.704846)
				)
			)
		)
	)
)
